(kicad_pcb
	(version 20260206)
	(generator "pcbnew")
	(generator_version "10.0")
	(general
		(thickness 1.6)
		(legacy_teardrops no)
	)
	(paper "A4")
	(title_block
		(title "03242023_DA0F0TMBIJ0_F0T_Motherboard_J_brd_V01_OCP.brd")
		(comment 1 "Grand Teton / footprints 2553-2557 of 6105")
	)
	(layers
		(0 "F.Cu" signal "TOP")
		(4 "In1.Cu" signal "GND")
		(6 "In2.Cu" signal "IN1")
		(8 "In3.Cu" signal "GND1")
		(10 "In4.Cu" signal "IN2")
		(12 "In5.Cu" signal "GND2")
		(14 "In6.Cu" signal "IN3")
		(16 "In7.Cu" signal "GND3")
		(18 "In8.Cu" signal "VCC")
		(20 "In9.Cu" signal "VCC1")
		(22 "In10.Cu" signal "GND4")
		(24 "In11.Cu" signal "IN4")
		(26 "In12.Cu" signal "GND5")
		(28 "In13.Cu" signal "IN5")
		(30 "In14.Cu" signal "GND6")
		(32 "In15.Cu" signal "IN6")
		(34 "In16.Cu" signal "GND7")
		(2 "B.Cu" signal "BOTTOM")
		(9 "F.Adhes" user "F.Adhesive")
		(11 "B.Adhes" user "B.Adhesive")
		(13 "F.Paste" user "Package Geometry/Pastemask Top")
		(15 "B.Paste" user "Package Geometry/Pastemask Bottom")
		(5 "F.SilkS" user "Ref Des/Silkscreen Top")
		(7 "B.SilkS" user "Ref Des/Silkscreen Bottom")
		(1 "F.Mask" user "Board Geometry/Soldermask Top")
		(3 "B.Mask" user "Board Geometry/Soldermask Bottom")
		(17 "Dwgs.User" user "User.Drawings")
		(19 "Cmts.User" user "User.Comments")
		(21 "Eco1.User" user "User.Eco1")
		(23 "Eco2.User" user "User.Eco2")
		(25 "Edge.Cuts" user "Board Geometry/Outline")
		(27 "Margin" user)
		(31 "F.CrtYd" user "Package Geometry/Place Bound Top")
		(29 "B.CrtYd" user "Package Geometry/Place Bound Bottom")
		(35 "F.Fab" user "Ref Des/Assembly Top")
		(33 "B.Fab" user "Ref Des/Assembly Bottom")
	)
	(footprint ""
		(layer "F.Cu")
		(at 216.065608 -406.855422)
		(property "Reference" "PR3922"
			(at 0 0 0)
			(layer "F.SilkS")
			(hide yes)
			(effects
				(font
					(size 1.27 1.27)
				)
			)
		)
		(property "Value" ""
			(at 0 0 0)
			(layer "F.Fab")
			(effects
				(font
					(size 1.27 1.27)
				)
			)
		)
		(duplicate_pad_numbers_are_jumpers no)
		(fp_line
			(start -0.7874 -0.4064)
			(end 0.7874 -0.4064)
			(stroke
				(width 0.1524)
				(type default)
			)
			(layer "F.SilkS")
		)
		(fp_line
			(start -0.7874 0.4064)
			(end -0.7874 -0.4064)
			(stroke
				(width 0.1524)
				(type default)
			)
			(layer "F.SilkS")
		)
		(fp_line
			(start 0.7874 -0.4064)
			(end 0.7874 0.4064)
			(stroke
				(width 0.1524)
				(type default)
			)
			(layer "F.SilkS")
		)
		(fp_line
			(start 0.7874 0.4064)
			(end -0.7874 0.4064)
			(stroke
				(width 0.1524)
				(type default)
			)
			(layer "F.SilkS")
		)
		(fp_line
			(start -0.67945 -0.305054)
			(end -0.12065 -0.305054)
			(stroke
				(width 0.1)
				(type default)
			)
			(layer "F.Fab")
		)
		(fp_line
			(start -0.67945 0.3048)
			(end -0.67945 -0.305054)
			(stroke
				(width 0.1)
				(type default)
			)
			(layer "F.Fab")
		)
		(fp_line
			(start -0.12065 -0.305054)
			(end -0.12065 -0.2794)
			(stroke
				(width 0.1)
				(type default)
			)
			(layer "F.Fab")
		)
		(fp_line
			(start -0.12065 -0.2794)
			(end 0.12065 -0.2794)
			(stroke
				(width 0.1)
				(type default)
			)
			(layer "F.Fab")
		)
		(fp_line
			(start -0.12065 0.2794)
			(end -0.12065 0.3048)
			(stroke
				(width 0.1)
				(type default)
			)
			(layer "F.Fab")
		)
		(fp_line
			(start -0.12065 0.3048)
			(end -0.67945 0.3048)
			(stroke
				(width 0.1)
				(type default)
			)
			(layer "F.Fab")
		)
		(fp_line
			(start 0.120396 0.2794)
			(end -0.12065 0.2794)
			(stroke
				(width 0.1)
				(type default)
			)
			(layer "F.Fab")
		)
		(fp_line
			(start 0.120396 0.3048)
			(end 0.120396 0.2794)
			(stroke
				(width 0.1)
				(type default)
			)
			(layer "F.Fab")
		)
		(fp_line
			(start 0.12065 -0.3048)
			(end 0.67945 -0.3048)
			(stroke
				(width 0.1)
				(type default)
			)
			(layer "F.Fab")
		)
		(fp_line
			(start 0.12065 -0.2794)
			(end 0.12065 -0.3048)
			(stroke
				(width 0.1)
				(type default)
			)
			(layer "F.Fab")
		)
		(fp_line
			(start 0.67945 -0.3048)
			(end 0.67945 0.3048)
			(stroke
				(width 0.1)
				(type default)
			)
			(layer "F.Fab")
		)
		(fp_line
			(start 0.67945 0.3048)
			(end 0.120396 0.3048)
			(stroke
				(width 0.1)
				(type default)
			)
			(layer "F.Fab")
		)
		(pad "1" smd circle
			(at -0.40005 0)
			(size 0 0)
			(layers "F.Cu" "F.Mask" "F.Paste")
			(net "HSC_FLT_TYPE_2")
		)
		(pad "2" smd circle
			(at 0.40005 0)
			(size 0 0)
			(layers "F.Cu" "F.Mask" "F.Paste")
			(net "HSC_FLT_TYPE")
		)
	)
	(footprint ""
		(layer "F.Cu")
		(at 434.06568 -178.069748 180)
		(property "Reference" "PC27"
			(at 0 0 180)
			(layer "F.SilkS")
			(hide yes)
			(effects
				(font
					(size 1.27 1.27)
				)
			)
		)
		(property "Value" ""
			(at 0 0 180)
			(layer "F.Fab")
			(effects
				(font
					(size 1.27 1.27)
				)
			)
		)
		(duplicate_pad_numbers_are_jumpers no)
		(fp_line
			(start 0.7874 0.4064)
			(end -0.7874 0.4064)
			(stroke
				(width 0.1524)
				(type default)
			)
			(layer "F.SilkS")
		)
		(fp_line
			(start 0.7874 -0.4064)
			(end 0.7874 0.4064)
			(stroke
				(width 0.1524)
				(type default)
			)
			(layer "F.SilkS")
		)
		(fp_line
			(start -0.7874 0.4064)
			(end -0.7874 -0.4064)
			(stroke
				(width 0.1524)
				(type default)
			)
			(layer "F.SilkS")
		)
		(fp_line
			(start -0.7874 -0.4064)
			(end 0.7874 -0.4064)
			(stroke
				(width 0.1524)
				(type default)
			)
			(layer "F.SilkS")
		)
		(fp_line
			(start 0.67945 0.3048)
			(end 0.120396 0.3048)
			(stroke
				(width 0.1)
				(type default)
			)
			(layer "F.Fab")
		)
		(fp_line
			(start 0.67945 -0.3048)
			(end 0.67945 0.3048)
			(stroke
				(width 0.1)
				(type default)
			)
			(layer "F.Fab")
		)
		(fp_line
			(start 0.12065 -0.2794)
			(end 0.12065 -0.3048)
			(stroke
				(width 0.1)
				(type default)
			)
			(layer "F.Fab")
		)
		(fp_line
			(start 0.12065 -0.3048)
			(end 0.67945 -0.3048)
			(stroke
				(width 0.1)
				(type default)
			)
			(layer "F.Fab")
		)
		(fp_line
			(start 0.120396 0.3048)
			(end 0.120396 0.2794)
			(stroke
				(width 0.1)
				(type default)
			)
			(layer "F.Fab")
		)
		(fp_line
			(start 0.120396 0.2794)
			(end -0.12065 0.2794)
			(stroke
				(width 0.1)
				(type default)
			)
			(layer "F.Fab")
		)
		(fp_line
			(start -0.12065 0.3048)
			(end -0.67945 0.3048)
			(stroke
				(width 0.1)
				(type default)
			)
			(layer "F.Fab")
		)
		(fp_line
			(start -0.12065 0.2794)
			(end -0.12065 0.3048)
			(stroke
				(width 0.1)
				(type default)
			)
			(layer "F.Fab")
		)
		(fp_line
			(start -0.12065 -0.2794)
			(end 0.12065 -0.2794)
			(stroke
				(width 0.1)
				(type default)
			)
			(layer "F.Fab")
		)
		(fp_line
			(start -0.12065 -0.305054)
			(end -0.12065 -0.2794)
			(stroke
				(width 0.1)
				(type default)
			)
			(layer "F.Fab")
		)
		(fp_line
			(start -0.67945 0.3048)
			(end -0.67945 -0.305054)
			(stroke
				(width 0.1)
				(type default)
			)
			(layer "F.Fab")
		)
		(fp_line
			(start -0.67945 -0.305054)
			(end -0.12065 -0.305054)
			(stroke
				(width 0.1)
				(type default)
			)
			(layer "F.Fab")
		)
		(pad "1" smd circle
			(at -0.40005 0 180)
			(size 0 0)
			(layers "F.Cu" "F.Mask" "F.Paste")
			(net "PVNN_MAIN_CPU0_REF")
		)
		(pad "2" smd circle
			(at 0.40005 0 180)
			(size 0 0)
			(layers "F.Cu" "F.Mask" "F.Paste")
			(net "GND")
		)
	)
	(footprint ""
		(layer "F.Cu")
		(at 485.20985 -216.092532 -90)
		(property "Reference" "X42"
			(at -0.1778 -1.92913 270)
			(unlocked yes)
			(layer "F.SilkS")
			(effects
				(font
					(size 0.7874 0.5842)
					(thickness 0.1524)
				)
				(justify left)
			)
		)
		(property "Value" ""
			(at 0 0 270)
			(layer "F.Fab")
			(effects
				(font
					(size 1.27 1.27)
				)
			)
		)
		(property "Device Type" "TP_TDR_4P_FTS_TH-TP_TDR_4P_DIPA"
			(at 1.30175 1.27 0)
			(unlocked yes)
			(layer "F.Fab")
			(hide yes)
			(effects
				(font
					(size 0.635 0.4064)
					(thickness 0.1524)
				)
			)
		)
		(property "User Part Number" "N_A"
			(at 1.30175 1.27 0)
			(unlocked yes)
			(layer "Cmts.User")
			(hide yes)
			(effects
				(font
					(size 0.635 0.4064)
					(thickness 0.1524)
				)
			)
		)
		(duplicate_pad_numbers_are_jumpers no)
		(fp_line
			(start 0 3.81)
			(end 2.54 3.81)
			(stroke
				(width 0.1524)
				(type default)
			)
			(layer "F.SilkS")
		)
		(fp_line
			(start 2.54 3.81)
			(end 2.54 3.6703)
			(stroke
				(width 0.1524)
				(type default)
			)
			(layer "F.SilkS")
		)
		(fp_line
			(start 0 3.175)
			(end 0 3.81)
			(stroke
				(width 0.1524)
				(type default)
			)
			(layer "F.SilkS")
		)
		(fp_line
			(start 2.54 1.4097)
			(end 2.54 1.1303)
			(stroke
				(width 0.1524)
				(type default)
			)
			(layer "F.SilkS")
		)
		(fp_line
			(start 0 0.635)
			(end 0 1.905)
			(stroke
				(width 0.1524)
				(type default)
			)
			(layer "F.SilkS")
		)
		(fp_line
			(start 2.54 -1.1303)
			(end 2.54 -1.27)
			(stroke
				(width 0.1524)
				(type default)
			)
			(layer "F.SilkS")
		)
		(fp_line
			(start 0 -1.27)
			(end 0 -0.635)
			(stroke
				(width 0.1524)
				(type default)
			)
			(layer "F.SilkS")
		)
		(fp_line
			(start 2.54 -1.27)
			(end 0 -1.27)
			(stroke
				(width 0.1524)
				(type default)
			)
			(layer "F.SilkS")
		)
		(fp_poly
			(pts
				(xy -0.761746 0) (xy -2.285746 -0.762) (xy -2.285746 0.762)
			)
			(stroke
				(width 0)
				(type default)
			)
			(fill yes)
			(layer "F.SilkS")
		)
		(fp_line
			(start 0 3.81)
			(end 2.54 3.81)
			(stroke
				(width 0.1)
				(type default)
			)
			(layer "F.Fab")
		)
		(fp_line
			(start 2.54 3.81)
			(end 2.54 -1.27)
			(stroke
				(width 0.1)
				(type default)
			)
			(layer "F.Fab")
		)
		(fp_line
			(start 0 -1.27)
			(end 0 3.81)
			(stroke
				(width 0.1)
				(type default)
			)
			(layer "F.Fab")
		)
		(fp_line
			(start 2.54 -1.27)
			(end 0 -1.27)
			(stroke
				(width 0.1)
				(type default)
			)
			(layer "F.Fab")
		)
		(fp_poly
			(pts
				(xy -0.761746 0) (xy -2.285746 -0.762) (xy -2.285746 0.762)
			)
			(stroke
				(width 0)
				(type default)
			)
			(fill yes)
			(layer "F.Fab")
		)
		(pad "1" thru_hole circle
			(at 0 0 270)
			(size 1.0033 1.0033)
			(drill 0.249936)
			(layers "*.Cu" "*.Mask")
			(remove_unused_layers no)
			(net "TDR_DIFF_85_NECK_IN1_DN")
			(clearance 0.10795)
			(thermal_gap 0.10795)
			(padstack
				(mode front_inner_back)
				(layer "Inner"
					(shape circle)
					(size 0.8001 0.8001)
					(clearance 0.1524)
				)
				(layer "B.Cu"
					(shape circle)
					(size 1.0033 1.0033)
					(clearance 0.10795)
				)
			)
		)
		(pad "2" thru_hole circle
			(at 2.54 0 270)
			(size 1.9939 1.9939)
			(drill 0.249936)
			(layers "*.Cu" "*.Mask")
			(remove_unused_layers no)
			(net "T1_GND")
			(clearance 0.10795)
			(thermal_gap 0.10795)
			(padstack
				(mode front_inner_back)
				(layer "Inner"
					(shape circle)
					(size 0.8001 0.8001)
					(clearance 0.1524)
				)
				(layer "B.Cu"
					(shape circle)
					(size 1.9939 1.9939)
					(clearance 0.10795)
				)
			)
		)
		(pad "3" thru_hole circle
			(at 2.54 2.54 270)
			(size 1.9939 1.9939)
			(drill 0.249936)
			(layers "*.Cu" "*.Mask")
			(remove_unused_layers no)
			(net "T1_GND")
			(clearance 0.10795)
			(thermal_gap 0.10795)
			(padstack
				(mode front_inner_back)
				(layer "Inner"
					(shape circle)
					(size 0.8001 0.8001)
					(clearance 0.1524)
				)
				(layer "B.Cu"
					(shape circle)
					(size 1.9939 1.9939)
					(clearance 0.10795)
				)
			)
		)
		(pad "4" thru_hole circle
			(at 0 2.54 270)
			(size 1.0033 1.0033)
			(drill 0.249936)
			(layers "*.Cu" "*.Mask")
			(remove_unused_layers no)
			(net "TDR_DIFF_85_NECK_IN1_DP")
			(clearance 0.10795)
			(thermal_gap 0.10795)
			(padstack
				(mode front_inner_back)
				(layer "Inner"
					(shape circle)
					(size 0.8001 0.8001)
					(clearance 0.1524)
				)
				(layer "B.Cu"
					(shape circle)
					(size 1.0033 1.0033)
					(clearance 0.10795)
				)
			)
		)
	)
	(footprint ""
		(layer "F.Cu")
		(at 187.221622 -22.727158 -90)
		(property "Reference" "PR4001"
			(at 0 0 270)
			(layer "F.SilkS")
			(hide yes)
			(effects
				(font
					(size 1.27 1.27)
				)
			)
		)
		(property "Value" ""
			(at 0 0 270)
			(layer "F.Fab")
			(effects
				(font
					(size 1.27 1.27)
				)
			)
		)
		(duplicate_pad_numbers_are_jumpers no)
		(fp_line
			(start -0.7874 0.4064)
			(end -0.7874 -0.4064)
			(stroke
				(width 0.1524)
				(type default)
			)
			(layer "F.SilkS")
		)
		(fp_line
			(start 0.7874 0.4064)
			(end -0.7874 0.4064)
			(stroke
				(width 0.1524)
				(type default)
			)
			(layer "F.SilkS")
		)
		(fp_line
			(start -0.7874 -0.4064)
			(end 0.7874 -0.4064)
			(stroke
				(width 0.1524)
				(type default)
			)
			(layer "F.SilkS")
		)
		(fp_line
			(start 0.7874 -0.4064)
			(end 0.7874 0.4064)
			(stroke
				(width 0.1524)
				(type default)
			)
			(layer "F.SilkS")
		)
		(fp_line
			(start -0.67945 0.3048)
			(end -0.67945 -0.305054)
			(stroke
				(width 0.1)
				(type default)
			)
			(layer "F.Fab")
		)
		(fp_line
			(start -0.12065 0.3048)
			(end -0.67945 0.3048)
			(stroke
				(width 0.1)
				(type default)
			)
			(layer "F.Fab")
		)
		(fp_line
			(start 0.120396 0.3048)
			(end 0.120396 0.2794)
			(stroke
				(width 0.1)
				(type default)
			)
			(layer "F.Fab")
		)
		(fp_line
			(start 0.67945 0.3048)
			(end 0.120396 0.3048)
			(stroke
				(width 0.1)
				(type default)
			)
			(layer "F.Fab")
		)
		(fp_line
			(start -0.12065 0.2794)
			(end -0.12065 0.3048)
			(stroke
				(width 0.1)
				(type default)
			)
			(layer "F.Fab")
		)
		(fp_line
			(start 0.120396 0.2794)
			(end -0.12065 0.2794)
			(stroke
				(width 0.1)
				(type default)
			)
			(layer "F.Fab")
		)
		(fp_line
			(start -0.12065 -0.2794)
			(end 0.12065 -0.2794)
			(stroke
				(width 0.1)
				(type default)
			)
			(layer "F.Fab")
		)
		(fp_line
			(start 0.12065 -0.2794)
			(end 0.12065 -0.3048)
			(stroke
				(width 0.1)
				(type default)
			)
			(layer "F.Fab")
		)
		(fp_line
			(start 0.12065 -0.3048)
			(end 0.67945 -0.3048)
			(stroke
				(width 0.1)
				(type default)
			)
			(layer "F.Fab")
		)
		(fp_line
			(start 0.67945 -0.3048)
			(end 0.67945 0.3048)
			(stroke
				(width 0.1)
				(type default)
			)
			(layer "F.Fab")
		)
		(fp_line
			(start -0.67945 -0.305054)
			(end -0.12065 -0.305054)
			(stroke
				(width 0.1)
				(type default)
			)
			(layer "F.Fab")
		)
		(fp_line
			(start -0.12065 -0.305054)
			(end -0.12065 -0.2794)
			(stroke
				(width 0.1)
				(type default)
			)
			(layer "F.Fab")
		)
		(pad "1" smd circle
			(at -0.40005 0 270)
			(size 0 0)
			(layers "F.Cu" "F.Mask" "F.Paste")
			(net "P12V_SCM_UV")
		)
		(pad "2" smd circle
			(at 0.40005 0 270)
			(size 0 0)
			(layers "F.Cu" "F.Mask" "F.Paste")
			(net "P12V_SCM_OV")
		)
	)
	(footprint ""
		(layer "F.Cu")
		(at 353.266248 -247.715024 90)
		(property "Reference" "C971"
			(at 0 0 90)
			(layer "F.SilkS")
			(hide yes)
			(effects
				(font
					(size 1.27 1.27)
				)
			)
		)
		(property "Value" ""
			(at 0 0 90)
			(layer "F.Fab")
			(effects
				(font
					(size 1.27 1.27)
				)
			)
		)
		(duplicate_pad_numbers_are_jumpers no)
		(fp_line
			(start 0.7874 -0.4064)
			(end 0.7874 0.4064)
			(stroke
				(width 0.1524)
				(type default)
			)
			(layer "F.SilkS")
		)
		(fp_line
			(start -0.7874 -0.4064)
			(end 0.7874 -0.4064)
			(stroke
				(width 0.1524)
				(type default)
			)
			(layer "F.SilkS")
		)
		(fp_line
			(start 0.7874 0.4064)
			(end -0.7874 0.4064)
			(stroke
				(width 0.1524)
				(type default)
			)
			(layer "F.SilkS")
		)
		(fp_line
			(start -0.7874 0.4064)
			(end -0.7874 -0.4064)
			(stroke
				(width 0.1524)
				(type default)
			)
			(layer "F.SilkS")
		)
		(fp_line
			(start -0.12065 -0.305054)
			(end -0.12065 -0.2794)
			(stroke
				(width 0.1)
				(type default)
			)
			(layer "F.Fab")
		)
		(fp_line
			(start -0.67945 -0.305054)
			(end -0.12065 -0.305054)
			(stroke
				(width 0.1)
				(type default)
			)
			(layer "F.Fab")
		)
		(fp_line
			(start 0.67945 -0.3048)
			(end 0.67945 0.3048)
			(stroke
				(width 0.1)
				(type default)
			)
			(layer "F.Fab")
		)
		(fp_line
			(start 0.12065 -0.3048)
			(end 0.67945 -0.3048)
			(stroke
				(width 0.1)
				(type default)
			)
			(layer "F.Fab")
		)
		(fp_line
			(start 0.12065 -0.2794)
			(end 0.12065 -0.3048)
			(stroke
				(width 0.1)
				(type default)
			)
			(layer "F.Fab")
		)
		(fp_line
			(start -0.12065 -0.2794)
			(end 0.12065 -0.2794)
			(stroke
				(width 0.1)
				(type default)
			)
			(layer "F.Fab")
		)
		(fp_line
			(start 0.120396 0.2794)
			(end -0.12065 0.2794)
			(stroke
				(width 0.1)
				(type default)
			)
			(layer "F.Fab")
		)
		(fp_line
			(start -0.12065 0.2794)
			(end -0.12065 0.3048)
			(stroke
				(width 0.1)
				(type default)
			)
			(layer "F.Fab")
		)
		(fp_line
			(start 0.67945 0.3048)
			(end 0.120396 0.3048)
			(stroke
				(width 0.1)
				(type default)
			)
			(layer "F.Fab")
		)
		(fp_line
			(start 0.120396 0.3048)
			(end 0.120396 0.2794)
			(stroke
				(width 0.1)
				(type default)
			)
			(layer "F.Fab")
		)
		(fp_line
			(start -0.12065 0.3048)
			(end -0.67945 0.3048)
			(stroke
				(width 0.1)
				(type default)
			)
			(layer "F.Fab")
		)
		(fp_line
			(start -0.67945 0.3048)
			(end -0.67945 -0.305054)
			(stroke
				(width 0.1)
				(type default)
			)
			(layer "F.Fab")
		)
		(pad "1" smd circle
			(at -0.40005 0 90)
			(size 0 0)
			(layers "F.Cu" "F.Mask" "F.Paste")
			(net "PVCCIN_CPU0")
		)
		(pad "2" smd circle
			(at 0.40005 0 90)
			(size 0 0)
			(layers "F.Cu" "F.Mask" "F.Paste")
			(net "GND")
		)
	)
)
